# S9S_MB_2U (Grand Teton) — schematic netlist excerpt (pin names and nets, part order shuffled) for the footprints in the layout excerpt that follows; sources: Cadence DE-HDL packaged netlist, KiCad conversion of 03242023_DA0F0TMBIJ0_F0T_Motherboard_J_brd_V01_OCP.brd

C93  Q_CAP  2.2UF 6.3V 20% X6S  pkg C0402  page 106 : A = P3V3_AUX ; B = GND
R171  Q_RES  0 5% CHIP  pkg 0402LF  page 124 : A = RST_CPU0_LVC1_R_N ; B = RST_CPU0_BUF_R_N

(kicad_pcb
	(version 20260206)
	(generator "pcbnew")
	(generator_version "10.0")
	(general
		(thickness 1.6)
		(legacy_teardrops no)
	)
	(paper "A4")
	(title_block
		(title "03242023_DA0F0TMBIJ0_F0T_Motherboard_J_brd_V01_OCP.brd")
		(comment 1 "Grand Teton / footprints 4220-4221 of 6105")
	)
	(layers
		(0 "F.Cu" signal "TOP")
		(4 "In1.Cu" signal "GND")
		(6 "In2.Cu" signal "IN1")
		(8 "In3.Cu" signal "GND1")
		(10 "In4.Cu" signal "IN2")
		(12 "In5.Cu" signal "GND2")
		(14 "In6.Cu" signal "IN3")
		(16 "In7.Cu" signal "GND3")
		(18 "In8.Cu" signal "VCC")
		(20 "In9.Cu" signal "VCC1")
		(22 "In10.Cu" signal "GND4")
		(24 "In11.Cu" signal "IN4")
		(26 "In12.Cu" signal "GND5")
		(28 "In13.Cu" signal "IN5")
		(30 "In14.Cu" signal "GND6")
		(32 "In15.Cu" signal "IN6")
		(34 "In16.Cu" signal "GND7")
		(2 "B.Cu" signal "BOTTOM")
		(9 "F.Adhes" user "F.Adhesive")
		(11 "B.Adhes" user "B.Adhesive")
		(13 "F.Paste" user "Package Geometry/Pastemask Top")
		(15 "B.Paste" user "Package Geometry/Pastemask Bottom")
		(5 "F.SilkS" user "Ref Des/Silkscreen Top")
		(7 "B.SilkS" user "Ref Des/Silkscreen Bottom")
		(1 "F.Mask" user "Board Geometry/Soldermask Top")
		(3 "B.Mask" user "Board Geometry/Soldermask Bottom")
		(17 "Dwgs.User" user "User.Drawings")
		(19 "Cmts.User" user "User.Comments")
		(21 "Eco1.User" user "User.Eco1")
		(23 "Eco2.User" user "User.Eco2")
		(25 "Edge.Cuts" user "Board Geometry/Outline")
		(27 "Margin" user)
		(31 "F.CrtYd" user "Package Geometry/Place Bound Top")
		(29 "B.CrtYd" user "Package Geometry/Place Bound Bottom")
		(35 "F.Fab" user "Ref Des/Assembly Top")
		(33 "B.Fab" user "Ref Des/Assembly Bottom")
	)
	(footprint ""
		(layer "B.Cu")
		(at 185.53684 -104.491028 180)
		(property "Reference" "R171"
			(at 0 0 0)
			(layer "B.SilkS")
			(hide yes)
			(effects
				(font
					(size 1.27 1.27)
				)
				(justify mirror)
			)
		)
		(property "Value" ""
			(at 0 0 0)
			(layer "B.Fab")
			(effects
				(font
					(size 1.27 1.27)
				)
				(justify mirror)
			)
		)
		(duplicate_pad_numbers_are_jumpers no)
		(fp_line
			(start 0.7874 0.4064)
			(end 0.7874 -0.4064)
			(stroke
				(width 0.1524)
				(type default)
			)
			(layer "B.SilkS")
		)
		(fp_line
			(start 0.7874 -0.4064)
			(end -0.7874 -0.4064)
			(stroke
				(width 0.1524)
				(type default)
			)
			(layer "B.SilkS")
		)
		(fp_line
			(start -0.7874 0.4064)
			(end 0.7874 0.4064)
			(stroke
				(width 0.1524)
				(type default)
			)
			(layer "B.SilkS")
		)
		(fp_line
			(start -0.7874 -0.4064)
			(end -0.7874 0.4064)
			(stroke
				(width 0.1524)
				(type default)
			)
			(layer "B.SilkS")
		)
		(fp_line
			(start 0.67945 0.3048)
			(end 0.67945 -0.305054)
			(stroke
				(width 0.1)
				(type default)
			)
			(layer "B.Fab")
		)
		(fp_line
			(start 0.67945 -0.305054)
			(end 0.12065 -0.305054)
			(stroke
				(width 0.1)
				(type default)
			)
			(layer "B.Fab")
		)
		(fp_line
			(start 0.12065 0.3048)
			(end 0.67945 0.3048)
			(stroke
				(width 0.1)
				(type default)
			)
			(layer "B.Fab")
		)
		(fp_line
			(start 0.12065 0.2794)
			(end 0.12065 0.3048)
			(stroke
				(width 0.1)
				(type default)
			)
			(layer "B.Fab")
		)
		(fp_line
			(start 0.12065 -0.2794)
			(end -0.12065 -0.2794)
			(stroke
				(width 0.1)
				(type default)
			)
			(layer "B.Fab")
		)
		(fp_line
			(start 0.12065 -0.305054)
			(end 0.12065 -0.2794)
			(stroke
				(width 0.1)
				(type default)
			)
			(layer "B.Fab")
		)
		(fp_line
			(start -0.120396 0.3048)
			(end -0.120396 0.2794)
			(stroke
				(width 0.1)
				(type default)
			)
			(layer "B.Fab")
		)
		(fp_line
			(start -0.120396 0.2794)
			(end 0.12065 0.2794)
			(stroke
				(width 0.1)
				(type default)
			)
			(layer "B.Fab")
		)
		(fp_line
			(start -0.12065 -0.2794)
			(end -0.12065 -0.3048)
			(stroke
				(width 0.1)
				(type default)
			)
			(layer "B.Fab")
		)
		(fp_line
			(start -0.12065 -0.3048)
			(end -0.67945 -0.3048)
			(stroke
				(width 0.1)
				(type default)
			)
			(layer "B.Fab")
		)
		(fp_line
			(start -0.67945 0.3048)
			(end -0.120396 0.3048)
			(stroke
				(width 0.1)
				(type default)
			)
			(layer "B.Fab")
		)
		(fp_line
			(start -0.67945 -0.3048)
			(end -0.67945 0.3048)
			(stroke
				(width 0.1)
				(type default)
			)
			(layer "B.Fab")
		)
		(pad "1" smd circle
			(at 0.40005 0)
			(size 0 0)
			(layers "B.Cu" "B.Mask" "B.Paste")
			(net "RST_CPU0_LVC1_R_N")
		)
		(pad "2" smd circle
			(at -0.40005 0)
			(size 0 0)
			(layers "B.Cu" "B.Mask" "B.Paste")
			(net "RST_CPU0_BUF_R_N")
		)
	)
	(footprint ""
		(layer "B.Cu")
		(at 166.369746 -319.268856 180)
		(property "Reference" "C93"
			(at 0 0 0)
			(layer "B.SilkS")
			(hide yes)
			(effects
				(font
					(size 1.27 1.27)
				)
				(justify mirror)
			)
		)
		(property "Value" ""
			(at 0 0 0)
			(layer "B.Fab")
			(effects
				(font
					(size 1.27 1.27)
				)
				(justify mirror)
			)
		)
		(duplicate_pad_numbers_are_jumpers no)
		(fp_line
			(start 0.7874 0.4064)
			(end 0.7874 -0.4064)
			(stroke
				(width 0.1524)
				(type default)
			)
			(layer "B.SilkS")
		)
		(fp_line
			(start 0.7874 -0.4064)
			(end -0.7874 -0.4064)
			(stroke
				(width 0.1524)
				(type default)
			)
			(layer "B.SilkS")
		)
		(fp_line
			(start -0.7874 0.4064)
			(end 0.7874 0.4064)
			(stroke
				(width 0.1524)
				(type default)
			)
			(layer "B.SilkS")
		)
		(fp_line
			(start -0.7874 -0.4064)
			(end -0.7874 0.4064)
			(stroke
				(width 0.1524)
				(type default)
			)
			(layer "B.SilkS")
		)
		(fp_line
			(start 0.67945 0.3048)
			(end 0.67945 -0.305054)
			(stroke
				(width 0.1)
				(type default)
			)
			(layer "B.Fab")
		)
		(fp_line
			(start 0.67945 -0.305054)
			(end 0.12065 -0.305054)
			(stroke
				(width 0.1)
				(type default)
			)
			(layer "B.Fab")
		)
		(fp_line
			(start 0.12065 0.3048)
			(end 0.67945 0.3048)
			(stroke
				(width 0.1)
				(type default)
			)
			(layer "B.Fab")
		)
		(fp_line
			(start 0.12065 0.2794)
			(end 0.12065 0.3048)
			(stroke
				(width 0.1)
				(type default)
			)
			(layer "B.Fab")
		)
		(fp_line
			(start 0.12065 -0.2794)
			(end -0.12065 -0.2794)
			(stroke
				(width 0.1)
				(type default)
			)
			(layer "B.Fab")
		)
		(fp_line
			(start 0.12065 -0.305054)
			(end 0.12065 -0.2794)
			(stroke
				(width 0.1)
				(type default)
			)
			(layer "B.Fab")
		)
		(fp_line
			(start -0.120396 0.3048)
			(end -0.120396 0.2794)
			(stroke
				(width 0.1)
				(type default)
			)
			(layer "B.Fab")
		)
		(fp_line
			(start -0.120396 0.2794)
			(end 0.12065 0.2794)
			(stroke
				(width 0.1)
				(type default)
			)
			(layer "B.Fab")
		)
		(fp_line
			(start -0.12065 -0.2794)
			(end -0.12065 -0.3048)
			(stroke
				(width 0.1)
				(type default)
			)
			(layer "B.Fab")
		)
		(fp_line
			(start -0.12065 -0.3048)
			(end -0.67945 -0.3048)
			(stroke
				(width 0.1)
				(type default)
			)
			(layer "B.Fab")
		)
		(fp_line
			(start -0.67945 0.3048)
			(end -0.120396 0.3048)
			(stroke
				(width 0.1)
				(type default)
			)
			(layer "B.Fab")
		)
		(fp_line
			(start -0.67945 -0.3048)
			(end -0.67945 0.3048)
			(stroke
				(width 0.1)
				(type default)
			)
			(layer "B.Fab")
		)
		(pad "1" smd circle
			(at 0.40005 0)
			(size 0 0)
			(layers "B.Cu" "B.Mask" "B.Paste")
			(net "P3V3_AUX")
		)
		(pad "2" smd circle
			(at -0.40005 0)
			(size 0 0)
			(layers "B.Cu" "B.Mask" "B.Paste")
			(net "GND")
		)
	)
)
